# S9S_MB_2U (Grand Teton) — schematic netlist excerpt (pin names and nets, part order shuffled) for the footprints in the layout excerpt that follows; sources: Cadence DE-HDL packaged netlist, KiCad conversion of 03242023_DA0F0TMBIJ0_F0T_Motherboard_J_brd_V01_OCP.brd

C2444  Q_CAP  0.1UF 25V 10% X7R  pkg 0402  page 278 : A = PVNN_TERM_CPU0 ; B = GND
R3664  Q_RES  10K 1% EMPTY  pkg 0402LF  page 152 : A = USB_HUB_PSELF ; B = GND

(kicad_pcb
	(version 20260206)
	(generator "pcbnew")
	(generator_version "10.0")
	(general
		(thickness 1.6)
		(legacy_teardrops no)
	)
	(paper "A4")
	(title_block
		(title "03242023_DA0F0TMBIJ0_F0T_Motherboard_J_brd_V01_OCP.brd")
		(comment 1 "Grand Teton / footprints 2214-2215 of 6105")
	)
	(layers
		(0 "F.Cu" signal "TOP")
		(4 "In1.Cu" signal "GND")
		(6 "In2.Cu" signal "IN1")
		(8 "In3.Cu" signal "GND1")
		(10 "In4.Cu" signal "IN2")
		(12 "In5.Cu" signal "GND2")
		(14 "In6.Cu" signal "IN3")
		(16 "In7.Cu" signal "GND3")
		(18 "In8.Cu" signal "VCC")
		(20 "In9.Cu" signal "VCC1")
		(22 "In10.Cu" signal "GND4")
		(24 "In11.Cu" signal "IN4")
		(26 "In12.Cu" signal "GND5")
		(28 "In13.Cu" signal "IN5")
		(30 "In14.Cu" signal "GND6")
		(32 "In15.Cu" signal "IN6")
		(34 "In16.Cu" signal "GND7")
		(2 "B.Cu" signal "BOTTOM")
		(9 "F.Adhes" user "F.Adhesive")
		(11 "B.Adhes" user "B.Adhesive")
		(13 "F.Paste" user "Package Geometry/Pastemask Top")
		(15 "B.Paste" user "Package Geometry/Pastemask Bottom")
		(5 "F.SilkS" user "Ref Des/Silkscreen Top")
		(7 "B.SilkS" user "Ref Des/Silkscreen Bottom")
		(1 "F.Mask" user "Board Geometry/Soldermask Top")
		(3 "B.Mask" user "Board Geometry/Soldermask Bottom")
		(17 "Dwgs.User" user "User.Drawings")
		(19 "Cmts.User" user "User.Comments")
		(21 "Eco1.User" user "User.Eco1")
		(23 "Eco2.User" user "User.Eco2")
		(25 "Edge.Cuts" user "Board Geometry/Outline")
		(27 "Margin" user)
		(31 "F.CrtYd" user "Package Geometry/Place Bound Top")
		(29 "B.CrtYd" user "Package Geometry/Place Bound Bottom")
		(35 "F.Fab" user "Ref Des/Assembly Top")
		(33 "B.Fab" user "Ref Des/Assembly Bottom")
	)
	(footprint ""
		(layer "F.Cu")
		(at 21.181314 -95.510604)
		(property "Reference" "R3664"
			(at 0 0 0)
			(layer "F.SilkS")
			(hide yes)
			(effects
				(font
					(size 1.27 1.27)
				)
			)
		)
		(property "Value" ""
			(at 0 0 0)
			(layer "F.Fab")
			(effects
				(font
					(size 1.27 1.27)
				)
			)
		)
		(duplicate_pad_numbers_are_jumpers no)
		(fp_line
			(start -0.7874 -0.4064)
			(end 0.7874 -0.4064)
			(stroke
				(width 0.1524)
				(type default)
			)
			(layer "F.SilkS")
		)
		(fp_line
			(start -0.7874 0.4064)
			(end -0.7874 -0.4064)
			(stroke
				(width 0.1524)
				(type default)
			)
			(layer "F.SilkS")
		)
		(fp_line
			(start 0.7874 -0.4064)
			(end 0.7874 0.4064)
			(stroke
				(width 0.1524)
				(type default)
			)
			(layer "F.SilkS")
		)
		(fp_line
			(start 0.7874 0.4064)
			(end -0.7874 0.4064)
			(stroke
				(width 0.1524)
				(type default)
			)
			(layer "F.SilkS")
		)
		(fp_line
			(start -0.67945 -0.305054)
			(end -0.12065 -0.305054)
			(stroke
				(width 0.1)
				(type default)
			)
			(layer "F.Fab")
		)
		(fp_line
			(start -0.67945 0.3048)
			(end -0.67945 -0.305054)
			(stroke
				(width 0.1)
				(type default)
			)
			(layer "F.Fab")
		)
		(fp_line
			(start -0.12065 -0.305054)
			(end -0.12065 -0.2794)
			(stroke
				(width 0.1)
				(type default)
			)
			(layer "F.Fab")
		)
		(fp_line
			(start -0.12065 -0.2794)
			(end 0.12065 -0.2794)
			(stroke
				(width 0.1)
				(type default)
			)
			(layer "F.Fab")
		)
		(fp_line
			(start -0.12065 0.2794)
			(end -0.12065 0.3048)
			(stroke
				(width 0.1)
				(type default)
			)
			(layer "F.Fab")
		)
		(fp_line
			(start -0.12065 0.3048)
			(end -0.67945 0.3048)
			(stroke
				(width 0.1)
				(type default)
			)
			(layer "F.Fab")
		)
		(fp_line
			(start 0.120396 0.2794)
			(end -0.12065 0.2794)
			(stroke
				(width 0.1)
				(type default)
			)
			(layer "F.Fab")
		)
		(fp_line
			(start 0.120396 0.3048)
			(end 0.120396 0.2794)
			(stroke
				(width 0.1)
				(type default)
			)
			(layer "F.Fab")
		)
		(fp_line
			(start 0.12065 -0.3048)
			(end 0.67945 -0.3048)
			(stroke
				(width 0.1)
				(type default)
			)
			(layer "F.Fab")
		)
		(fp_line
			(start 0.12065 -0.2794)
			(end 0.12065 -0.3048)
			(stroke
				(width 0.1)
				(type default)
			)
			(layer "F.Fab")
		)
		(fp_line
			(start 0.67945 -0.3048)
			(end 0.67945 0.3048)
			(stroke
				(width 0.1)
				(type default)
			)
			(layer "F.Fab")
		)
		(fp_line
			(start 0.67945 0.3048)
			(end 0.120396 0.3048)
			(stroke
				(width 0.1)
				(type default)
			)
			(layer "F.Fab")
		)
		(pad "1" smd circle
			(at -0.40005 0)
			(size 0 0)
			(layers "F.Cu" "F.Mask" "F.Paste")
			(net "USB_HUB_PSELF")
		)
		(pad "2" smd circle
			(at 0.40005 0)
			(size 0 0)
			(layers "F.Cu" "F.Mask" "F.Paste")
			(net "GND")
		)
	)
	(footprint ""
		(layer "F.Cu")
		(at 441.376054 -123.656598)
		(property "Reference" "C2444"
			(at 0 0 0)
			(layer "F.SilkS")
			(hide yes)
			(effects
				(font
					(size 1.27 1.27)
				)
			)
		)
		(property "Value" ""
			(at 0 0 0)
			(layer "F.Fab")
			(effects
				(font
					(size 1.27 1.27)
				)
			)
		)
		(duplicate_pad_numbers_are_jumpers no)
		(fp_line
			(start -0.7874 -0.4064)
			(end 0.7874 -0.4064)
			(stroke
				(width 0.1524)
				(type default)
			)
			(layer "F.SilkS")
		)
		(fp_line
			(start -0.7874 0.4064)
			(end -0.7874 -0.4064)
			(stroke
				(width 0.1524)
				(type default)
			)
			(layer "F.SilkS")
		)
		(fp_line
			(start 0.7874 -0.4064)
			(end 0.7874 0.4064)
			(stroke
				(width 0.1524)
				(type default)
			)
			(layer "F.SilkS")
		)
		(fp_line
			(start 0.7874 0.4064)
			(end -0.7874 0.4064)
			(stroke
				(width 0.1524)
				(type default)
			)
			(layer "F.SilkS")
		)
		(fp_line
			(start -0.67945 -0.305054)
			(end -0.12065 -0.305054)
			(stroke
				(width 0.1)
				(type default)
			)
			(layer "F.Fab")
		)
		(fp_line
			(start -0.67945 0.3048)
			(end -0.67945 -0.305054)
			(stroke
				(width 0.1)
				(type default)
			)
			(layer "F.Fab")
		)
		(fp_line
			(start -0.12065 -0.305054)
			(end -0.12065 -0.2794)
			(stroke
				(width 0.1)
				(type default)
			)
			(layer "F.Fab")
		)
		(fp_line
			(start -0.12065 -0.2794)
			(end 0.12065 -0.2794)
			(stroke
				(width 0.1)
				(type default)
			)
			(layer "F.Fab")
		)
		(fp_line
			(start -0.12065 0.2794)
			(end -0.12065 0.3048)
			(stroke
				(width 0.1)
				(type default)
			)
			(layer "F.Fab")
		)
		(fp_line
			(start -0.12065 0.3048)
			(end -0.67945 0.3048)
			(stroke
				(width 0.1)
				(type default)
			)
			(layer "F.Fab")
		)
		(fp_line
			(start 0.120396 0.2794)
			(end -0.12065 0.2794)
			(stroke
				(width 0.1)
				(type default)
			)
			(layer "F.Fab")
		)
		(fp_line
			(start 0.120396 0.3048)
			(end 0.120396 0.2794)
			(stroke
				(width 0.1)
				(type default)
			)
			(layer "F.Fab")
		)
		(fp_line
			(start 0.12065 -0.3048)
			(end 0.67945 -0.3048)
			(stroke
				(width 0.1)
				(type default)
			)
			(layer "F.Fab")
		)
		(fp_line
			(start 0.12065 -0.2794)
			(end 0.12065 -0.3048)
			(stroke
				(width 0.1)
				(type default)
			)
			(layer "F.Fab")
		)
		(fp_line
			(start 0.67945 -0.3048)
			(end 0.67945 0.3048)
			(stroke
				(width 0.1)
				(type default)
			)
			(layer "F.Fab")
		)
		(fp_line
			(start 0.67945 0.3048)
			(end 0.120396 0.3048)
			(stroke
				(width 0.1)
				(type default)
			)
			(layer "F.Fab")
		)
		(pad "1" smd circle
			(at -0.40005 0)
			(size 0 0)
			(layers "F.Cu" "F.Mask" "F.Paste")
			(net "PVNN_TERM_CPU0")
		)
		(pad "2" smd circle
			(at 0.40005 0)
			(size 0 0)
			(layers "F.Cu" "F.Mask" "F.Paste")
			(net "GND")
		)
	)
)
